FILE_TYPE=LIBRARY_PARTS;
primitive 'PT5161LRS';
  pin
    'A_PERP0':
      PIN_NUMBER='(R1,0,0,0,0,0,0,0,0,0,0)';
      INPUT_LOAD='(-0.01,0.01)';
    'A_PERN0':
      PIN_NUMBER='(N2,0,0,0,0,0,0,0,0,0,0)';
      INPUT_LOAD='(-0.01,0.01)';
    'A_PERP1':
      PIN_NUMBER='(AB1,0,0,0,0,0,0,0,0,0,0)';
      INPUT_LOAD='(-0.01,0.01)';
    'A_PERN1':
      PIN_NUMBER='(Y2,0,0,0,0,0,0,0,0,0,0)';
      INPUT_LOAD='(-0.01,0.01)';
    'A_PERP2':
      PIN_NUMBER='(AJ1,0,0,0,0,0,0,0,0,0,0)';
      INPUT_LOAD='(-0.01,0.01)';
    'A_PERN2':
      PIN_NUMBER='(AG2,0,0,0,0,0,0,0,0,0,0)';
      INPUT_LOAD='(-0.01,0.01)';
    'A_PERP3':
      PIN_NUMBER='(AT1,0,0,0,0,0,0,0,0,0,0)';
      INPUT_LOAD='(-0.01,0.01)';
    'A_PERN3':
      PIN_NUMBER='(AP2,0,0,0,0,0,0,0,0,0,0)';
      INPUT_LOAD='(-0.01,0.01)';
    'A_PERP4':
      PIN_NUMBER='(BC1,0,0,0,0,0,0,0,0,0,0)';
      INPUT_LOAD='(-0.01,0.01)';
    'A_PERN4':
      PIN_NUMBER='(BA2,0,0,0,0,0,0,0,0,0,0)';
      INPUT_LOAD='(-0.01,0.01)';
    'A_PERP5':
      PIN_NUMBER='(BK1,0,0,0,0,0,0,0,0,0,0)';
      INPUT_LOAD='(-0.01,0.01)';
    'A_PERN5':
      PIN_NUMBER='(BH2,0,0,0,0,0,0,0,0,0,0)';
      INPUT_LOAD='(-0.01,0.01)';
    'A_PERP6':
      PIN_NUMBER='(BU1,0,0,0,0,0,0,0,0,0,0)';
      INPUT_LOAD='(-0.01,0.01)';
    'A_PERN6':
      PIN_NUMBER='(BR2,0,0,0,0,0,0,0,0,0,0)';
      INPUT_LOAD='(-0.01,0.01)';
    'A_PERP7':
      PIN_NUMBER='(CD1,0,0,0,0,0,0,0,0,0,0)';
      INPUT_LOAD='(-0.01,0.01)';
    'A_PERN7':
      PIN_NUMBER='(CB2,0,0,0,0,0,0,0,0,0,0)';
      INPUT_LOAD='(-0.01,0.01)';
    'A_PERP8':
      PIN_NUMBER='(0,CL1,0,0,0,0,0,0,0,0,0)';
      INPUT_LOAD='(-0.01,0.01)';
    'A_PERN8':
      PIN_NUMBER='(0,CJ2,0,0,0,0,0,0,0,0,0)';
      INPUT_LOAD='(-0.01,0.01)';
    'A_PERP9':
      PIN_NUMBER='(0,CV1,0,0,0,0,0,0,0,0,0)';
      INPUT_LOAD='(-0.01,0.01)';
    'A_PERN9':
      PIN_NUMBER='(0,CT2,0,0,0,0,0,0,0,0,0)';
      INPUT_LOAD='(-0.01,0.01)';
    'A_PERP10':
      PIN_NUMBER='(0,DE1,0,0,0,0,0,0,0,0,0)';
      INPUT_LOAD='(-0.01,0.01)';
    'A_PERN10':
      PIN_NUMBER='(0,DC2,0,0,0,0,0,0,0,0,0)';
      INPUT_LOAD='(-0.01,0.01)';
    'A_PERP11':
      PIN_NUMBER='(0,DM1,0,0,0,0,0,0,0,0,0)';
      INPUT_LOAD='(-0.01,0.01)';
    'A_PERN11':
      PIN_NUMBER='(0,DK2,0,0,0,0,0,0,0,0,0)';
      INPUT_LOAD='(-0.01,0.01)';
    'A_PERP12':
      PIN_NUMBER='(0,DW1,0,0,0,0,0,0,0,0,0)';
      INPUT_LOAD='(-0.01,0.01)';
    'A_PERN12':
      PIN_NUMBER='(0,DU2,0,0,0,0,0,0,0,0,0)';
      INPUT_LOAD='(-0.01,0.01)';
    'A_PERP13':
      PIN_NUMBER='(0,EF1,0,0,0,0,0,0,0,0,0)';
      INPUT_LOAD='(-0.01,0.01)';
    'A_PERN13':
      PIN_NUMBER='(0,ED2,0,0,0,0,0,0,0,0,0)';
      INPUT_LOAD='(-0.01,0.01)';
    'A_PERP14':
      PIN_NUMBER='(0,EN1,0,0,0,0,0,0,0,0,0)';
      INPUT_LOAD='(-0.01,0.01)';
    'A_PERN14':
      PIN_NUMBER='(0,EL2,0,0,0,0,0,0,0,0,0)';
      INPUT_LOAD='(-0.01,0.01)';
    'A_PERP15':
      PIN_NUMBER='(0,EY1,0,0,0,0,0,0,0,0,0)';
      INPUT_LOAD='(-0.01,0.01)';
    'A_PERN15':
      PIN_NUMBER='(0,EV2,0,0,0,0,0,0,0,0,0)';
      INPUT_LOAD='(-0.01,0.01)';
    'GPIO0':
      PIN_NUMBER='(0,0,FJ6,0,0,0,0,0,0,0,0)';
      BIDIRECTIONAL='TRUE';
      INPUT_LOAD='(-0.01,0.01)';
      OUTPUT_LOAD='(1.0,-1.0)';
    'GPIO1':
      PIN_NUMBER='(0,0,FJ23,0,0,0,0,0,0,0,0)';
      BIDIRECTIONAL='TRUE';
      INPUT_LOAD='(-0.01,0.01)';
      OUTPUT_LOAD='(1.0,-1.0)';
    'GPIO2':
      PIN_NUMBER='(0,0,FJ25,0,0,0,0,0,0,0,0)';
      BIDIRECTIONAL='TRUE';
      INPUT_LOAD='(-0.01,0.01)';
      OUTPUT_LOAD='(1.0,-1.0)';
    'GPIO3':
      PIN_NUMBER='(0,0,FJ28,0,0,0,0,0,0,0,0)';
      BIDIRECTIONAL='TRUE';
      INPUT_LOAD='(-0.01,0.01)';
      OUTPUT_LOAD='(1.0,-1.0)';
    '-INT':
      PIN_NUMBER='(0,0,FJ31,0,0,0,0,0,0,0,0)';
      OUTPUT_LOAD='(1.0,-1.0)';
    'JTAG_TCK':
      PIN_NUMBER='(0,0,B3,0,0,0,0,0,0,0,0)';
      INPUT_LOAD='(-0.01,0.01)';
    'JTAG_TDI':
      PIN_NUMBER='(0,0,B6,0,0,0,0,0,0,0,0)';
      INPUT_LOAD='(-0.01,0.01)';
    'JTAG_TDO':
      PIN_NUMBER='(0,0,B9,0,0,0,0,0,0,0,0)';
      OUTPUT_LOAD='(1.0,-1.0)';
    'JTAG_TEST_MODE':
      PIN_NUMBER='(0,0,FF8,0,0,0,0,0,0,0,0)';
      INPUT_LOAD='(-0.01,0.01)';
    'JTAG_TMS':
      PIN_NUMBER='(0,0,B12,0,0,0,0,0,0,0,0)';
      INPUT_LOAD='(-0.01,0.01)';
    '-JTAG_TRST':
      PIN_NUMBER='(0,0,E8,0,0,0,0,0,0,0,0)';
      INPUT_LOAD='(-0.01,0.01)';
    'MODE':
      PIN_NUMBER='(0,0,FJ9,0,0,0,0,0,0,0,0)';
      INPUT_LOAD='(-0.01,0.01)';
    '-PERST':
      PIN_NUMBER='(0,0,F2,0,0,0,0,0,0,0,0)';
      INPUT_LOAD='(-0.01,0.01)';
    'REFCLK_OUTN':
      PIN_NUMBER='(0,0,E18,0,0,0,0,0,0,0,0)';
      OUTPUT_LOAD='(1.0,-1.0)';
    'REFCLK_OUTP':
      PIN_NUMBER='(0,0,B16,0,0,0,0,0,0,0,0)';
      OUTPUT_LOAD='(1.0,-1.0)';
    'REFCLKN':
      PIN_NUMBER='(0,0,FF18,0,0,0,0,0,0,0,0)';
      INPUT_LOAD='(-0.01,0.01)';
    'REFCLKP':
      PIN_NUMBER='(0,0,FJ16,0,0,0,0,0,0,0,0)';
      INPUT_LOAD='(-0.01,0.01)';
    '-RESET':
      PIN_NUMBER='(0,0,FF11,0,0,0,0,0,0,0,0)';
      INPUT_LOAD='(-0.01,0.01)';
    'RXDET_BYP':
      PIN_NUMBER='(0,0,E11,0,0,0,0,0,0,0,0)';
      INPUT_LOAD='(-0.01,0.01)';
    'SCAN_MODE':
      PIN_NUMBER='(0,0,FF33,0,0,0,0,0,0,0,0)';
      INPUT_LOAD='(-0.01,0.01)';
    'SMB_ADDR1':
      PIN_NUMBER='(0,0,F34,0,0,0,0,0,0,0,0)';
      INPUT_LOAD='(-0.01,0.01)';
    'SMB_ADDR2':
      PIN_NUMBER='(0,0,B23,0,0,0,0,0,0,0,0)';
      INPUT_LOAD='(-0.01,0.01)';
    'SMB_ADDR3':
      PIN_NUMBER='(0,0,B25,0,0,0,0,0,0,0,0)';
      INPUT_LOAD='(-0.01,0.01)';
    'SMBCLK':
      PIN_NUMBER='(0,0,B31,0,0,0,0,0,0,0,0)';
      BIDIRECTIONAL='TRUE';
      INPUT_LOAD='(-0.01,0.01)';
      OUTPUT_LOAD='(1.0,-1.0)';
    'SMBDAT':
      PIN_NUMBER='(0,0,B28,0,0,0,0,0,0,0,0)';
      BIDIRECTIONAL='TRUE';
      INPUT_LOAD='(-0.01,0.01)';
      OUTPUT_LOAD='(1.0,-1.0)';
    'T_SENSE':
      PIN_NUMBER='(0,0,E30,0,0,0,0,0,0,0,0)';
      OUTPUT_LOAD='(1.0,-1.0)';
    'TEST0':
      PIN_NUMBER='(0,0,FF24,0,0,0,0,0,0,0,0)';
      BIDIRECTIONAL='TRUE';
      INPUT_LOAD='(-0.01,0.01)';
      OUTPUT_LOAD='(1.0,-1.0)';
    'TEST1':
      PIN_NUMBER='(0,0,FF27,0,0,0,0,0,0,0,0)';
      BIDIRECTIONAL='TRUE';
      INPUT_LOAD='(-0.01,0.01)';
      OUTPUT_LOAD='(1.0,-1.0)';
    'TEST2':
      PIN_NUMBER='(0,0,FF30,0,0,0,0,0,0,0,0)';
      BIDIRECTIONAL='TRUE';
      INPUT_LOAD='(-0.01,0.01)';
      OUTPUT_LOAD='(1.0,-1.0)';
    '-CLKREQ':
      PIN_NUMBER='(0,0,G35,0,0,0,0,0,0,0,0)';
      INPUT_LOAD='(-0.01,0.01)';
    'EE_CLK':
      PIN_NUMBER='(0,0,FF5,0,0,0,0,0,0,0,0)';
      BIDIRECTIONAL='TRUE';
      INPUT_LOAD='(-0.01,0.01)';
      OUTPUT_LOAD='(1.0,-1.0)';
    'EE_DAT':
      PIN_NUMBER='(0,0,FJ3,0,0,0,0,0,0,0,0)';
      BIDIRECTIONAL='TRUE';
      INPUT_LOAD='(-0.01,0.01)';
      OUTPUT_LOAD='(1.0,-1.0)';
    'VQPS':
      PIN_NUMBER='(0,0,0,G1,0,0,0,0,0,0,0)';
      INPUT_LOAD='(-0.01,0.01)';
    'PWR_1A_1':
      PIN_NUMBER='(0,0,0,BV20,0,0,0,0,0,0,0)';
      PINUSE='POWER';
      NO_LOAD_CHECK='Both';
      NO_IO_CHECK='Both';
      NO_ASSERT_CHECK='TRUE';
      NO_DIR_CHECK='TRUE';
      ALLOW_CONNECT='TRUE';
    'PWR_1A_2':
      PIN_NUMBER='(0,0,0,CE17,0,0,0,0,0,0,0)';
      PINUSE='POWER';
      NO_LOAD_CHECK='Both';
      NO_IO_CHECK='Both';
      NO_ASSERT_CHECK='TRUE';
      NO_DIR_CHECK='TRUE';
      ALLOW_CONNECT='TRUE';
    'PWR_1A_3':
      PIN_NUMBER='(0,0,0,CE20,0,0,0,0,0,0,0)';
      PINUSE='POWER';
      NO_LOAD_CHECK='Both';
      NO_IO_CHECK='Both';
      NO_ASSERT_CHECK='TRUE';
      NO_DIR_CHECK='TRUE';
      ALLOW_CONNECT='TRUE';
    'PWR_1A_4':
      PIN_NUMBER='(0,0,0,CM17,0,0,0,0,0,0,0)';
      PINUSE='POWER';
      NO_LOAD_CHECK='Both';
      NO_IO_CHECK='Both';
      NO_ASSERT_CHECK='TRUE';
      NO_DIR_CHECK='TRUE';
      ALLOW_CONNECT='TRUE';
    'PWR_1A_5':
      PIN_NUMBER='(0,0,0,CM20,0,0,0,0,0,0,0)';
      PINUSE='POWER';
      NO_LOAD_CHECK='Both';
      NO_IO_CHECK='Both';
      NO_ASSERT_CHECK='TRUE';
      NO_DIR_CHECK='TRUE';
      ALLOW_CONNECT='TRUE';
    'PWR_2D_1':
      PIN_NUMBER='(0,0,0,BL17,0,0,0,0,0,0,0)';
      PINUSE='POWER';
      NO_LOAD_CHECK='Both';
      NO_IO_CHECK='Both';
      NO_ASSERT_CHECK='TRUE';
      NO_DIR_CHECK='TRUE';
      ALLOW_CONNECT='TRUE';
    'PWR_2D_2':
      PIN_NUMBER='(0,0,0,BL20,0,0,0,0,0,0,0)';
      PINUSE='POWER';
      NO_LOAD_CHECK='Both';
      NO_IO_CHECK='Both';
      NO_ASSERT_CHECK='TRUE';
      NO_DIR_CHECK='TRUE';
      ALLOW_CONNECT='TRUE';
    'PWR_2D_3':
      PIN_NUMBER='(0,0,0,CW17,0,0,0,0,0,0,0)';
      PINUSE='POWER';
      NO_LOAD_CHECK='Both';
      NO_IO_CHECK='Both';
      NO_ASSERT_CHECK='TRUE';
      NO_DIR_CHECK='TRUE';
      ALLOW_CONNECT='TRUE';
    'PWR_2D_4':
      PIN_NUMBER='(0,0,0,CW20,0,0,0,0,0,0,0)';
      PINUSE='POWER';
      NO_LOAD_CHECK='Both';
      NO_IO_CHECK='Both';
      NO_ASSERT_CHECK='TRUE';
      NO_DIR_CHECK='TRUE';
      ALLOW_CONNECT='TRUE';
    'PWR_1D':
      PIN_NUMBER='(0,0,0,BV17,0,0,0,0,0,0,0)';
      PINUSE='POWER';
      NO_LOAD_CHECK='Both';
      NO_IO_CHECK='Both';
      NO_ASSERT_CHECK='TRUE';
      NO_DIR_CHECK='TRUE';
      ALLOW_CONNECT='TRUE';
    'PWR_2A_1':
      PIN_NUMBER='(0,0,0,AC17,0,0,0,0,0,0,0)';
      PINUSE='POWER';
      NO_LOAD_CHECK='Both';
      NO_IO_CHECK='Both';
      NO_ASSERT_CHECK='TRUE';
      NO_DIR_CHECK='TRUE';
      ALLOW_CONNECT='TRUE';
    'PWR_2A_2':
      PIN_NUMBER='(0,0,0,AC20,0,0,0,0,0,0,0)';
      PINUSE='POWER';
      NO_LOAD_CHECK='Both';
      NO_IO_CHECK='Both';
      NO_ASSERT_CHECK='TRUE';
      NO_DIR_CHECK='TRUE';
      ALLOW_CONNECT='TRUE';
    'PWR_2A_3':
      PIN_NUMBER='(0,0,0,AK17,0,0,0,0,0,0,0)';
      PINUSE='POWER';
      NO_LOAD_CHECK='Both';
      NO_IO_CHECK='Both';
      NO_ASSERT_CHECK='TRUE';
      NO_DIR_CHECK='TRUE';
      ALLOW_CONNECT='TRUE';
    'PWR_2A_4':
      PIN_NUMBER='(0,0,0,AK20,0,0,0,0,0,0,0)';
      PINUSE='POWER';
      NO_LOAD_CHECK='Both';
      NO_IO_CHECK='Both';
      NO_ASSERT_CHECK='TRUE';
      NO_DIR_CHECK='TRUE';
      ALLOW_CONNECT='TRUE';
    'PWR_2A_5':
      PIN_NUMBER='(0,0,0,AU17,0,0,0,0,0,0,0)';
      PINUSE='POWER';
      NO_LOAD_CHECK='Both';
      NO_IO_CHECK='Both';
      NO_ASSERT_CHECK='TRUE';
      NO_DIR_CHECK='TRUE';
      ALLOW_CONNECT='TRUE';
    'PWR_2A_6':
      PIN_NUMBER='(0,0,0,AU20,0,0,0,0,0,0,0)';
      PINUSE='POWER';
      NO_LOAD_CHECK='Both';
      NO_IO_CHECK='Both';
      NO_ASSERT_CHECK='TRUE';
      NO_DIR_CHECK='TRUE';
      ALLOW_CONNECT='TRUE';
    'PWR_2A_7':
      PIN_NUMBER='(0,0,0,BD17,0,0,0,0,0,0,0)';
      PINUSE='POWER';
      NO_LOAD_CHECK='Both';
      NO_IO_CHECK='Both';
      NO_ASSERT_CHECK='TRUE';
      NO_DIR_CHECK='TRUE';
      ALLOW_CONNECT='TRUE';
    'PWR_2A_8':
      PIN_NUMBER='(0,0,0,BD20,0,0,0,0,0,0,0)';
      PINUSE='POWER';
      NO_LOAD_CHECK='Both';
      NO_IO_CHECK='Both';
      NO_ASSERT_CHECK='TRUE';
      NO_DIR_CHECK='TRUE';
      ALLOW_CONNECT='TRUE';
    'PWR_2A_9':
      PIN_NUMBER='(0,0,0,DF17,0,0,0,0,0,0,0)';
      PINUSE='POWER';
      NO_LOAD_CHECK='Both';
      NO_IO_CHECK='Both';
      NO_ASSERT_CHECK='TRUE';
      NO_DIR_CHECK='TRUE';
      ALLOW_CONNECT='TRUE';
    'PWR_2A_10':
      PIN_NUMBER='(0,0,0,DF20,0,0,0,0,0,0,0)';
      PINUSE='POWER';
      NO_LOAD_CHECK='Both';
      NO_IO_CHECK='Both';
      NO_ASSERT_CHECK='TRUE';
      NO_DIR_CHECK='TRUE';
      ALLOW_CONNECT='TRUE';
    'PWR_2A_11':
      PIN_NUMBER='(0,0,0,DN17,0,0,0,0,0,0,0)';
      PINUSE='POWER';
      NO_LOAD_CHECK='Both';
      NO_IO_CHECK='Both';
      NO_ASSERT_CHECK='TRUE';
      NO_DIR_CHECK='TRUE';
      ALLOW_CONNECT='TRUE';
    'PWR_2A_12':
      PIN_NUMBER='(0,0,0,DN20,0,0,0,0,0,0,0)';
      PINUSE='POWER';
      NO_LOAD_CHECK='Both';
      NO_IO_CHECK='Both';
      NO_ASSERT_CHECK='TRUE';
      NO_DIR_CHECK='TRUE';
      ALLOW_CONNECT='TRUE';
    'PWR_2A_13':
      PIN_NUMBER='(0,0,0,DY17,0,0,0,0,0,0,0)';
      PINUSE='POWER';
      NO_LOAD_CHECK='Both';
      NO_IO_CHECK='Both';
      NO_ASSERT_CHECK='TRUE';
      NO_DIR_CHECK='TRUE';
      ALLOW_CONNECT='TRUE';
    'PWR_2A_14':
      PIN_NUMBER='(0,0,0,DY20,0,0,0,0,0,0,0)';
      PINUSE='POWER';
      NO_LOAD_CHECK='Both';
      NO_IO_CHECK='Both';
      NO_ASSERT_CHECK='TRUE';
      NO_DIR_CHECK='TRUE';
      ALLOW_CONNECT='TRUE';
    'PWR_2A_15':
      PIN_NUMBER='(0,0,0,EG17,0,0,0,0,0,0,0)';
      PINUSE='POWER';
      NO_LOAD_CHECK='Both';
      NO_IO_CHECK='Both';
      NO_ASSERT_CHECK='TRUE';
      NO_DIR_CHECK='TRUE';
      ALLOW_CONNECT='TRUE';
    'PWR_2A_16':
      PIN_NUMBER='(0,0,0,EG20,0,0,0,0,0,0,0)';
      PINUSE='POWER';
      NO_LOAD_CHECK='Both';
      NO_IO_CHECK='Both';
      NO_ASSERT_CHECK='TRUE';
      NO_DIR_CHECK='TRUE';
      ALLOW_CONNECT='TRUE';
    'PWR_2A_17':
      PIN_NUMBER='(0,0,0,EP17,0,0,0,0,0,0,0)';
      PINUSE='POWER';
      NO_LOAD_CHECK='Both';
      NO_IO_CHECK='Both';
      NO_ASSERT_CHECK='TRUE';
      NO_DIR_CHECK='TRUE';
      ALLOW_CONNECT='TRUE';
    'PWR_2A_18':
      PIN_NUMBER='(0,0,0,EP20,0,0,0,0,0,0,0)';
      PINUSE='POWER';
      NO_LOAD_CHECK='Both';
      NO_IO_CHECK='Both';
      NO_ASSERT_CHECK='TRUE';
      NO_DIR_CHECK='TRUE';
      ALLOW_CONNECT='TRUE';
    'PWR_2A_19':
      PIN_NUMBER='(0,0,0,T17,0,0,0,0,0,0,0)';
      PINUSE='POWER';
      NO_LOAD_CHECK='Both';
      NO_IO_CHECK='Both';
      NO_ASSERT_CHECK='TRUE';
      NO_DIR_CHECK='TRUE';
      ALLOW_CONNECT='TRUE';
    'PWR_2A_20':
      PIN_NUMBER='(0,0,0,T20,0,0,0,0,0,0,0)';
      PINUSE='POWER';
      NO_LOAD_CHECK='Both';
      NO_IO_CHECK='Both';
      NO_ASSERT_CHECK='TRUE';
      NO_DIR_CHECK='TRUE';
      ALLOW_CONNECT='TRUE';
    'GND1':
      PIN_NUMBER='(0,0,0,0,AC13,0,0,0,0,0,0)';
      PINUSE='POWER';
      NO_LOAD_CHECK='Both';
      NO_IO_CHECK='Both';
      NO_ASSERT_CHECK='TRUE';
      NO_DIR_CHECK='TRUE';
      ALLOW_CONNECT='TRUE';
    'GND2':
      PIN_NUMBER='(0,0,0,0,AC22,0,0,0,0,0,0)';
      PINUSE='POWER';
      NO_LOAD_CHECK='Both';
      NO_IO_CHECK='Both';
      NO_ASSERT_CHECK='TRUE';
      NO_DIR_CHECK='TRUE';
      ALLOW_CONNECT='TRUE';
    'GND3':
      PIN_NUMBER='(0,0,0,0,AC32,0,0,0,0,0,0)';
      PINUSE='POWER';
      NO_LOAD_CHECK='Both';
      NO_IO_CHECK='Both';
      NO_ASSERT_CHECK='TRUE';
      NO_DIR_CHECK='TRUE';
      ALLOW_CONNECT='TRUE';
    'GND4':
      PIN_NUMBER='(0,0,0,0,AC4,0,0,0,0,0,0)';
      PINUSE='POWER';
      NO_LOAD_CHECK='Both';
      NO_IO_CHECK='Both';
      NO_ASSERT_CHECK='TRUE';
      NO_DIR_CHECK='TRUE';
      ALLOW_CONNECT='TRUE';
    'GND5':
      PIN_NUMBER='(0,0,0,0,AD2,0,0,0,0,0,0)';
      PINUSE='POWER';
      NO_LOAD_CHECK='Both';
      NO_IO_CHECK='Both';
      NO_ASSERT_CHECK='TRUE';
      NO_DIR_CHECK='TRUE';
      ALLOW_CONNECT='TRUE';
    'GND6':
      PIN_NUMBER='(0,0,0,0,AD34,0,0,0,0,0,0)';
      PINUSE='POWER';
      NO_LOAD_CHECK='Both';
      NO_IO_CHECK='Both';
      NO_ASSERT_CHECK='TRUE';
      NO_DIR_CHECK='TRUE';
      ALLOW_CONNECT='TRUE';
    'GND7':
      PIN_NUMBER='(0,0,0,0,AE1,0,0,0,0,0,0)';
      PINUSE='POWER';
      NO_LOAD_CHECK='Both';
      NO_IO_CHECK='Both';
      NO_ASSERT_CHECK='TRUE';
      NO_DIR_CHECK='TRUE';
      ALLOW_CONNECT='TRUE';
    'GND8':
      PIN_NUMBER='(0,0,0,0,AE35,0,0,0,0,0,0)';
      PINUSE='POWER';
      NO_LOAD_CHECK='Both';
      NO_IO_CHECK='Both';
      NO_ASSERT_CHECK='TRUE';
      NO_DIR_CHECK='TRUE';
      ALLOW_CONNECT='TRUE';
    'GND9':
      PIN_NUMBER='(0,0,0,0,AK13,0,0,0,0,0,0)';
      PINUSE='POWER';
      NO_LOAD_CHECK='Both';
      NO_IO_CHECK='Both';
      NO_ASSERT_CHECK='TRUE';
      NO_DIR_CHECK='TRUE';
      ALLOW_CONNECT='TRUE';
    'GND10':
      PIN_NUMBER='(0,0,0,0,AK22,0,0,0,0,0,0)';
      PINUSE='POWER';
      NO_LOAD_CHECK='Both';
      NO_IO_CHECK='Both';
      NO_ASSERT_CHECK='TRUE';
      NO_DIR_CHECK='TRUE';
      ALLOW_CONNECT='TRUE';
    'GND11':
      PIN_NUMBER='(0,0,0,0,AK32,0,0,0,0,0,0)';
      PINUSE='POWER';
      NO_LOAD_CHECK='Both';
      NO_IO_CHECK='Both';
      NO_ASSERT_CHECK='TRUE';
      NO_DIR_CHECK='TRUE';
      ALLOW_CONNECT='TRUE';
    'GND12':
      PIN_NUMBER='(0,0,0,0,AK4,0,0,0,0,0,0)';
      PINUSE='POWER';
      NO_LOAD_CHECK='Both';
      NO_IO_CHECK='Both';
      NO_ASSERT_CHECK='TRUE';
      NO_DIR_CHECK='TRUE';
      ALLOW_CONNECT='TRUE';
    'GND13':
      PIN_NUMBER='(0,0,0,0,AL2,0,0,0,0,0,0)';
      PINUSE='POWER';
      NO_LOAD_CHECK='Both';
      NO_IO_CHECK='Both';
      NO_ASSERT_CHECK='TRUE';
      NO_DIR_CHECK='TRUE';
      ALLOW_CONNECT='TRUE';
    'GND14':
      PIN_NUMBER='(0,0,0,0,AL34,0,0,0,0,0,0)';
      PINUSE='POWER';
      NO_LOAD_CHECK='Both';
      NO_IO_CHECK='Both';
      NO_ASSERT_CHECK='TRUE';
      NO_DIR_CHECK='TRUE';
      ALLOW_CONNECT='TRUE';
    'GND15':
      PIN_NUMBER='(0,0,0,0,AM1,0,0,0,0,0,0)';
      PINUSE='POWER';
      NO_LOAD_CHECK='Both';
      NO_IO_CHECK='Both';
      NO_ASSERT_CHECK='TRUE';
      NO_DIR_CHECK='TRUE';
      ALLOW_CONNECT='TRUE';
    'GND16':
      PIN_NUMBER='(0,0,0,0,AM35,0,0,0,0,0,0)';
      PINUSE='POWER';
      NO_LOAD_CHECK='Both';
      NO_IO_CHECK='Both';
      NO_ASSERT_CHECK='TRUE';
      NO_DIR_CHECK='TRUE';
      ALLOW_CONNECT='TRUE';
    'GND17':
      PIN_NUMBER='(0,0,0,0,AU13,0,0,0,0,0,0)';
      PINUSE='POWER';
      NO_LOAD_CHECK='Both';
      NO_IO_CHECK='Both';
      NO_ASSERT_CHECK='TRUE';
      NO_DIR_CHECK='TRUE';
      ALLOW_CONNECT='TRUE';
    'GND18':
      PIN_NUMBER='(0,0,0,0,AU22,0,0,0,0,0,0)';
      PINUSE='POWER';
      NO_LOAD_CHECK='Both';
      NO_IO_CHECK='Both';
      NO_ASSERT_CHECK='TRUE';
      NO_DIR_CHECK='TRUE';
      ALLOW_CONNECT='TRUE';
    'GND19':
      PIN_NUMBER='(0,0,0,0,AU32,0,0,0,0,0,0)';
      PINUSE='POWER';
      NO_LOAD_CHECK='Both';
      NO_IO_CHECK='Both';
      NO_ASSERT_CHECK='TRUE';
      NO_DIR_CHECK='TRUE';
      ALLOW_CONNECT='TRUE';
    'GND20':
      PIN_NUMBER='(0,0,0,0,AU4,0,0,0,0,0,0)';
      PINUSE='POWER';
      NO_LOAD_CHECK='Both';
      NO_IO_CHECK='Both';
      NO_ASSERT_CHECK='TRUE';
      NO_DIR_CHECK='TRUE';
      ALLOW_CONNECT='TRUE';
    'GND21':
      PIN_NUMBER='(0,0,0,0,AV2,0,0,0,0,0,0)';
      PINUSE='POWER';
      NO_LOAD_CHECK='Both';
      NO_IO_CHECK='Both';
      NO_ASSERT_CHECK='TRUE';
      NO_DIR_CHECK='TRUE';
      ALLOW_CONNECT='TRUE';
    'GND22':
      PIN_NUMBER='(0,0,0,0,AV34,0,0,0,0,0,0)';
      PINUSE='POWER';
      NO_LOAD_CHECK='Both';
      NO_IO_CHECK='Both';
      NO_ASSERT_CHECK='TRUE';
      NO_DIR_CHECK='TRUE';
      ALLOW_CONNECT='TRUE';
    'GND23':
      PIN_NUMBER='(0,0,0,0,AW1,0,0,0,0,0,0)';
      PINUSE='POWER';
      NO_LOAD_CHECK='Both';
      NO_IO_CHECK='Both';
      NO_ASSERT_CHECK='TRUE';
      NO_DIR_CHECK='TRUE';
      ALLOW_CONNECT='TRUE';
    'GND24':
      PIN_NUMBER='(0,0,0,0,AW35,0,0,0,0,0,0)';
      PINUSE='POWER';
      NO_LOAD_CHECK='Both';
      NO_IO_CHECK='Both';
      NO_ASSERT_CHECK='TRUE';
      NO_DIR_CHECK='TRUE';
      ALLOW_CONNECT='TRUE';
    'GND25':
      PIN_NUMBER='(0,0,0,0,B19,0,0,0,0,0,0)';
      PINUSE='POWER';
      NO_LOAD_CHECK='Both';
      NO_IO_CHECK='Both';
      NO_ASSERT_CHECK='TRUE';
      NO_DIR_CHECK='TRUE';
      ALLOW_CONNECT='TRUE';
    'GND26':
      PIN_NUMBER='(0,0,0,0,BD13,0,0,0,0,0,0)';
      PINUSE='POWER';
      NO_LOAD_CHECK='Both';
      NO_IO_CHECK='Both';
      NO_ASSERT_CHECK='TRUE';
      NO_DIR_CHECK='TRUE';
      ALLOW_CONNECT='TRUE';
    'GND27':
      PIN_NUMBER='(0,0,0,0,BD22,0,0,0,0,0,0)';
      PINUSE='POWER';
      NO_LOAD_CHECK='Both';
      NO_IO_CHECK='Both';
      NO_ASSERT_CHECK='TRUE';
      NO_DIR_CHECK='TRUE';
      ALLOW_CONNECT='TRUE';
    'GND28':
      PIN_NUMBER='(0,0,0,0,BD32,0,0,0,0,0,0)';
      PINUSE='POWER';
      NO_LOAD_CHECK='Both';
      NO_IO_CHECK='Both';
      NO_ASSERT_CHECK='TRUE';
      NO_DIR_CHECK='TRUE';
      ALLOW_CONNECT='TRUE';
    'GND29':
      PIN_NUMBER='(0,0,0,0,BD4,0,0,0,0,0,0)';
      PINUSE='POWER';
      NO_LOAD_CHECK='Both';
      NO_IO_CHECK='Both';
      NO_ASSERT_CHECK='TRUE';
      NO_DIR_CHECK='TRUE';
      ALLOW_CONNECT='TRUE';
    'GND30':
      PIN_NUMBER='(0,0,0,0,BE2,0,0,0,0,0,0)';
      PINUSE='POWER';
      NO_LOAD_CHECK='Both';
      NO_IO_CHECK='Both';
      NO_ASSERT_CHECK='TRUE';
      NO_DIR_CHECK='TRUE';
      ALLOW_CONNECT='TRUE';
    'GND31':
      PIN_NUMBER='(0,0,0,0,BE34,0,0,0,0,0,0)';
      PINUSE='POWER';
      NO_LOAD_CHECK='Both';
      NO_IO_CHECK='Both';
      NO_ASSERT_CHECK='TRUE';
      NO_DIR_CHECK='TRUE';
      ALLOW_CONNECT='TRUE';
    'GND32':
      PIN_NUMBER='(0,0,0,0,BF1,0,0,0,0,0,0)';
      PINUSE='POWER';
      NO_LOAD_CHECK='Both';
      NO_IO_CHECK='Both';
      NO_ASSERT_CHECK='TRUE';
      NO_DIR_CHECK='TRUE';
      ALLOW_CONNECT='TRUE';
    'GND33':
      PIN_NUMBER='(0,0,0,0,BF35,0,0,0,0,0,0)';
      PINUSE='POWER';
      NO_LOAD_CHECK='Both';
      NO_IO_CHECK='Both';
      NO_ASSERT_CHECK='TRUE';
      NO_DIR_CHECK='TRUE';
      ALLOW_CONNECT='TRUE';
    'GND34':
      PIN_NUMBER='(0,0,0,0,BL13,0,0,0,0,0,0)';
      PINUSE='POWER';
      NO_LOAD_CHECK='Both';
      NO_IO_CHECK='Both';
      NO_ASSERT_CHECK='TRUE';
      NO_DIR_CHECK='TRUE';
      ALLOW_CONNECT='TRUE';
    'GND35':
      PIN_NUMBER='(0,0,0,0,BL22,0,0,0,0,0,0)';
      PINUSE='POWER';
      NO_LOAD_CHECK='Both';
      NO_IO_CHECK='Both';
      NO_ASSERT_CHECK='TRUE';
      NO_DIR_CHECK='TRUE';
      ALLOW_CONNECT='TRUE';
    'GND36':
      PIN_NUMBER='(0,0,0,0,BL32,0,0,0,0,0,0)';
      PINUSE='POWER';
      NO_LOAD_CHECK='Both';
      NO_IO_CHECK='Both';
      NO_ASSERT_CHECK='TRUE';
      NO_DIR_CHECK='TRUE';
      ALLOW_CONNECT='TRUE';
    'GND37':
      PIN_NUMBER='(0,0,0,0,BL4,0,0,0,0,0,0)';
      PINUSE='POWER';
      NO_LOAD_CHECK='Both';
      NO_IO_CHECK='Both';
      NO_ASSERT_CHECK='TRUE';
      NO_DIR_CHECK='TRUE';
      ALLOW_CONNECT='TRUE';
    'GND38':
      PIN_NUMBER='(0,0,0,0,BM2,0,0,0,0,0,0)';
      PINUSE='POWER';
      NO_LOAD_CHECK='Both';
      NO_IO_CHECK='Both';
      NO_ASSERT_CHECK='TRUE';
      NO_DIR_CHECK='TRUE';
      ALLOW_CONNECT='TRUE';
    'GND39':
      PIN_NUMBER='(0,0,0,0,BM34,0,0,0,0,0,0)';
      PINUSE='POWER';
      NO_LOAD_CHECK='Both';
      NO_IO_CHECK='Both';
      NO_ASSERT_CHECK='TRUE';
      NO_DIR_CHECK='TRUE';
      ALLOW_CONNECT='TRUE';
    'GND40':
      PIN_NUMBER='(0,0,0,0,BN1,0,0,0,0,0,0)';
      PINUSE='POWER';
      NO_LOAD_CHECK='Both';
      NO_IO_CHECK='Both';
      NO_ASSERT_CHECK='TRUE';
      NO_DIR_CHECK='TRUE';
      ALLOW_CONNECT='TRUE';
    'GND41':
      PIN_NUMBER='(0,0,0,0,BN35,0,0,0,0,0,0)';
      PINUSE='POWER';
      NO_LOAD_CHECK='Both';
      NO_IO_CHECK='Both';
      NO_ASSERT_CHECK='TRUE';
      NO_DIR_CHECK='TRUE';
      ALLOW_CONNECT='TRUE';
    'GND42':
      PIN_NUMBER='(0,0,0,0,BV13,0,0,0,0,0,0)';
      PINUSE='POWER';
      NO_LOAD_CHECK='Both';
      NO_IO_CHECK='Both';
      NO_ASSERT_CHECK='TRUE';
      NO_DIR_CHECK='TRUE';
      ALLOW_CONNECT='TRUE';
    'GND43':
      PIN_NUMBER='(0,0,0,0,BV22,0,0,0,0,0,0)';
      PINUSE='POWER';
      NO_LOAD_CHECK='Both';
      NO_IO_CHECK='Both';
      NO_ASSERT_CHECK='TRUE';
      NO_DIR_CHECK='TRUE';
      ALLOW_CONNECT='TRUE';
    'GND44':
      PIN_NUMBER='(0,0,0,0,BV32,0,0,0,0,0,0)';
      PINUSE='POWER';
      NO_LOAD_CHECK='Both';
      NO_IO_CHECK='Both';
      NO_ASSERT_CHECK='TRUE';
      NO_DIR_CHECK='TRUE';
      ALLOW_CONNECT='TRUE';
    'GND45':
      PIN_NUMBER='(0,0,0,0,BV4,0,0,0,0,0,0)';
      PINUSE='POWER';
      NO_LOAD_CHECK='Both';
      NO_IO_CHECK='Both';
      NO_ASSERT_CHECK='TRUE';
      NO_DIR_CHECK='TRUE';
      ALLOW_CONNECT='TRUE';
    'GND46':
      PIN_NUMBER='(0,0,0,0,BW2,0,0,0,0,0,0)';
      PINUSE='POWER';
      NO_LOAD_CHECK='Both';
      NO_IO_CHECK='Both';
      NO_ASSERT_CHECK='TRUE';
      NO_DIR_CHECK='TRUE';
      ALLOW_CONNECT='TRUE';
    'GND47':
      PIN_NUMBER='(0,0,0,0,BW34,0,0,0,0,0,0)';
      PINUSE='POWER';
      NO_LOAD_CHECK='Both';
      NO_IO_CHECK='Both';
      NO_ASSERT_CHECK='TRUE';
      NO_DIR_CHECK='TRUE';
      ALLOW_CONNECT='TRUE';
    'GND48':
      PIN_NUMBER='(0,0,0,0,BY1,0,0,0,0,0,0)';
      PINUSE='POWER';
      NO_LOAD_CHECK='Both';
      NO_IO_CHECK='Both';
      NO_ASSERT_CHECK='TRUE';
      NO_DIR_CHECK='TRUE';
      ALLOW_CONNECT='TRUE';
    'GND49':
      PIN_NUMBER='(0,0,0,0,BY35,0,0,0,0,0,0)';
      PINUSE='POWER';
      NO_LOAD_CHECK='Both';
      NO_IO_CHECK='Both';
      NO_ASSERT_CHECK='TRUE';
      NO_DIR_CHECK='TRUE';
      ALLOW_CONNECT='TRUE';
    'GND50':
      PIN_NUMBER='(0,0,0,0,CE13,0,0,0,0,0,0)';
      PINUSE='POWER';
      NO_LOAD_CHECK='Both';
      NO_IO_CHECK='Both';
      NO_ASSERT_CHECK='TRUE';
      NO_DIR_CHECK='TRUE';
      ALLOW_CONNECT='TRUE';
    'GND51':
      PIN_NUMBER='(0,0,0,0,CE22,0,0,0,0,0,0)';
      PINUSE='POWER';
      NO_LOAD_CHECK='Both';
      NO_IO_CHECK='Both';
      NO_ASSERT_CHECK='TRUE';
      NO_DIR_CHECK='TRUE';
      ALLOW_CONNECT='TRUE';
    'GND52':
      PIN_NUMBER='(0,0,0,0,CE32,0,0,0,0,0,0)';
      PINUSE='POWER';
      NO_LOAD_CHECK='Both';
      NO_IO_CHECK='Both';
      NO_ASSERT_CHECK='TRUE';
      NO_DIR_CHECK='TRUE';
      ALLOW_CONNECT='TRUE';
    'GND53':
      PIN_NUMBER='(0,0,0,0,CE4,0,0,0,0,0,0)';
      PINUSE='POWER';
      NO_LOAD_CHECK='Both';
      NO_IO_CHECK='Both';
      NO_ASSERT_CHECK='TRUE';
      NO_DIR_CHECK='TRUE';
      ALLOW_CONNECT='TRUE';
    'GND54':
      PIN_NUMBER='(0,0,0,0,CF2,0,0,0,0,0,0)';
      PINUSE='POWER';
      NO_LOAD_CHECK='Both';
      NO_IO_CHECK='Both';
      NO_ASSERT_CHECK='TRUE';
      NO_DIR_CHECK='TRUE';
      ALLOW_CONNECT='TRUE';
    'GND55':
      PIN_NUMBER='(0,0,0,0,CF34,0,0,0,0,0,0)';
      PINUSE='POWER';
      NO_LOAD_CHECK='Both';
      NO_IO_CHECK='Both';
      NO_ASSERT_CHECK='TRUE';
      NO_DIR_CHECK='TRUE';
      ALLOW_CONNECT='TRUE';
    'GND56':
      PIN_NUMBER='(0,0,0,0,CG1,0,0,0,0,0,0)';
      PINUSE='POWER';
      NO_LOAD_CHECK='Both';
      NO_IO_CHECK='Both';
      NO_ASSERT_CHECK='TRUE';
      NO_DIR_CHECK='TRUE';
      ALLOW_CONNECT='TRUE';
    'GND57':
      PIN_NUMBER='(0,0,0,0,CG35,0,0,0,0,0,0)';
      PINUSE='POWER';
      NO_LOAD_CHECK='Both';
      NO_IO_CHECK='Both';
      NO_ASSERT_CHECK='TRUE';
      NO_DIR_CHECK='TRUE';
      ALLOW_CONNECT='TRUE';
    'GND58':
      PIN_NUMBER='(0,0,0,0,CM13,0,0,0,0,0,0)';
      PINUSE='POWER';
      NO_LOAD_CHECK='Both';
      NO_IO_CHECK='Both';
      NO_ASSERT_CHECK='TRUE';
      NO_DIR_CHECK='TRUE';
      ALLOW_CONNECT='TRUE';
    'GND59':
      PIN_NUMBER='(0,0,0,0,CM22,0,0,0,0,0,0)';
      PINUSE='POWER';
      NO_LOAD_CHECK='Both';
      NO_IO_CHECK='Both';
      NO_ASSERT_CHECK='TRUE';
      NO_DIR_CHECK='TRUE';
      ALLOW_CONNECT='TRUE';
    'GND60':
      PIN_NUMBER='(0,0,0,0,CM32,0,0,0,0,0,0)';
      PINUSE='POWER';
      NO_LOAD_CHECK='Both';
      NO_IO_CHECK='Both';
      NO_ASSERT_CHECK='TRUE';
      NO_DIR_CHECK='TRUE';
      ALLOW_CONNECT='TRUE';
    'GND61':
      PIN_NUMBER='(0,0,0,0,CM4,0,0,0,0,0,0)';
      PINUSE='POWER';
      NO_LOAD_CHECK='Both';
      NO_IO_CHECK='Both';
      NO_ASSERT_CHECK='TRUE';
      NO_DIR_CHECK='TRUE';
      ALLOW_CONNECT='TRUE';
    'GND62':
      PIN_NUMBER='(0,0,0,0,CN2,0,0,0,0,0,0)';
      PINUSE='POWER';
      NO_LOAD_CHECK='Both';
      NO_IO_CHECK='Both';
      NO_ASSERT_CHECK='TRUE';
      NO_DIR_CHECK='TRUE';
      ALLOW_CONNECT='TRUE';
    'GND63':
      PIN_NUMBER='(0,0,0,0,CN34,0,0,0,0,0,0)';
      PINUSE='POWER';
      NO_LOAD_CHECK='Both';
      NO_IO_CHECK='Both';
      NO_ASSERT_CHECK='TRUE';
      NO_DIR_CHECK='TRUE';
      ALLOW_CONNECT='TRUE';
    'GND64':
      PIN_NUMBER='(0,0,0,0,CP1,0,0,0,0,0,0)';
      PINUSE='POWER';
      NO_LOAD_CHECK='Both';
      NO_IO_CHECK='Both';
      NO_ASSERT_CHECK='TRUE';
      NO_DIR_CHECK='TRUE';
      ALLOW_CONNECT='TRUE';
    'GND65':
      PIN_NUMBER='(0,0,0,0,CP35,0,0,0,0,0,0)';
      PINUSE='POWER';
      NO_LOAD_CHECK='Both';
      NO_IO_CHECK='Both';
      NO_ASSERT_CHECK='TRUE';
      NO_DIR_CHECK='TRUE';
      ALLOW_CONNECT='TRUE';
    'GND66':
      PIN_NUMBER='(0,0,0,0,CW13,0,0,0,0,0,0)';
      PINUSE='POWER';
      NO_LOAD_CHECK='Both';
      NO_IO_CHECK='Both';
      NO_ASSERT_CHECK='TRUE';
      NO_DIR_CHECK='TRUE';
      ALLOW_CONNECT='TRUE';
    'GND67':
      PIN_NUMBER='(0,0,0,0,CW22,0,0,0,0,0,0)';
      PINUSE='POWER';
      NO_LOAD_CHECK='Both';
      NO_IO_CHECK='Both';
      NO_ASSERT_CHECK='TRUE';
      NO_DIR_CHECK='TRUE';
      ALLOW_CONNECT='TRUE';
    'GND68':
      PIN_NUMBER='(0,0,0,0,CW32,0,0,0,0,0,0)';
      PINUSE='POWER';
      NO_LOAD_CHECK='Both';
      NO_IO_CHECK='Both';
      NO_ASSERT_CHECK='TRUE';
      NO_DIR_CHECK='TRUE';
      ALLOW_CONNECT='TRUE';
    'GND69':
      PIN_NUMBER='(0,0,0,0,CW4,0,0,0,0,0,0)';
      PINUSE='POWER';
      NO_LOAD_CHECK='Both';
      NO_IO_CHECK='Both';
      NO_ASSERT_CHECK='TRUE';
      NO_DIR_CHECK='TRUE';
      ALLOW_CONNECT='TRUE';
    'GND70':
      PIN_NUMBER='(0,0,0,0,CY2,0,0,0,0,0,0)';
      PINUSE='POWER';
      NO_LOAD_CHECK='Both';
      NO_IO_CHECK='Both';
      NO_ASSERT_CHECK='TRUE';
      NO_DIR_CHECK='TRUE';
      ALLOW_CONNECT='TRUE';
    'GND71':
      PIN_NUMBER='(0,0,0,0,CY34,0,0,0,0,0,0)';
      PINUSE='POWER';
      NO_LOAD_CHECK='Both';
      NO_IO_CHECK='Both';
      NO_ASSERT_CHECK='TRUE';
      NO_DIR_CHECK='TRUE';
      ALLOW_CONNECT='TRUE';
    'GND72':
      PIN_NUMBER='(0,0,0,0,DA1,0,0,0,0,0,0)';
      PINUSE='POWER';
      NO_LOAD_CHECK='Both';
      NO_IO_CHECK='Both';
      NO_ASSERT_CHECK='TRUE';
      NO_DIR_CHECK='TRUE';
      ALLOW_CONNECT='TRUE';
    'GND73':
      PIN_NUMBER='(0,0,0,0,DA35,0,0,0,0,0,0)';
      PINUSE='POWER';
      NO_LOAD_CHECK='Both';
      NO_IO_CHECK='Both';
      NO_ASSERT_CHECK='TRUE';
      NO_DIR_CHECK='TRUE';
      ALLOW_CONNECT='TRUE';
    'GND74':
      PIN_NUMBER='(0,0,0,0,DF13,0,0,0,0,0,0)';
      PINUSE='POWER';
      NO_LOAD_CHECK='Both';
      NO_IO_CHECK='Both';
      NO_ASSERT_CHECK='TRUE';
      NO_DIR_CHECK='TRUE';
      ALLOW_CONNECT='TRUE';
    'GND75':
      PIN_NUMBER='(0,0,0,0,DF22,0,0,0,0,0,0)';
      PINUSE='POWER';
      NO_LOAD_CHECK='Both';
      NO_IO_CHECK='Both';
      NO_ASSERT_CHECK='TRUE';
      NO_DIR_CHECK='TRUE';
      ALLOW_CONNECT='TRUE';
    'GND76':
      PIN_NUMBER='(0,0,0,0,DF32,0,0,0,0,0,0)';
      PINUSE='POWER';
      NO_LOAD_CHECK='Both';
      NO_IO_CHECK='Both';
      NO_ASSERT_CHECK='TRUE';
      NO_DIR_CHECK='TRUE';
      ALLOW_CONNECT='TRUE';
    'GND77':
      PIN_NUMBER='(0,0,0,0,DF4,0,0,0,0,0,0)';
      PINUSE='POWER';
      NO_LOAD_CHECK='Both';
      NO_IO_CHECK='Both';
      NO_ASSERT_CHECK='TRUE';
      NO_DIR_CHECK='TRUE';
      ALLOW_CONNECT='TRUE';
    'GND78':
      PIN_NUMBER='(0,0,0,0,DG2,0,0,0,0,0,0)';
      PINUSE='POWER';
      NO_LOAD_CHECK='Both';
      NO_IO_CHECK='Both';
      NO_ASSERT_CHECK='TRUE';
      NO_DIR_CHECK='TRUE';
      ALLOW_CONNECT='TRUE';
    'GND79':
      PIN_NUMBER='(0,0,0,0,DG34,0,0,0,0,0,0)';
      PINUSE='POWER';
      NO_LOAD_CHECK='Both';
      NO_IO_CHECK='Both';
      NO_ASSERT_CHECK='TRUE';
      NO_DIR_CHECK='TRUE';
      ALLOW_CONNECT='TRUE';
    'GND80':
      PIN_NUMBER='(0,0,0,0,DH1,0,0,0,0,0,0)';
      PINUSE='POWER';
      NO_LOAD_CHECK='Both';
      NO_IO_CHECK='Both';
      NO_ASSERT_CHECK='TRUE';
      NO_DIR_CHECK='TRUE';
      ALLOW_CONNECT='TRUE';
    'GND81':
      PIN_NUMBER='(0,0,0,0,DH35,0,0,0,0,0,0)';
      PINUSE='POWER';
      NO_LOAD_CHECK='Both';
      NO_IO_CHECK='Both';
      NO_ASSERT_CHECK='TRUE';
      NO_DIR_CHECK='TRUE';
      ALLOW_CONNECT='TRUE';
    'GND82':
      PIN_NUMBER='(0,0,0,0,DN13,0,0,0,0,0,0)';
      PINUSE='POWER';
      NO_LOAD_CHECK='Both';
      NO_IO_CHECK='Both';
      NO_ASSERT_CHECK='TRUE';
      NO_DIR_CHECK='TRUE';
      ALLOW_CONNECT='TRUE';
    'NCF_GND1':
      PIN_NUMBER='(0,0,0,0,A1,0,0,0,0,0,0)';
      PINUSE='POWER';
      NO_LOAD_CHECK='Both';
      NO_IO_CHECK='Both';
      NO_ASSERT_CHECK='TRUE';
      NO_DIR_CHECK='TRUE';
      ALLOW_CONNECT='TRUE';
    'NCF_GND2':
      PIN_NUMBER='(0,0,0,0,A35,0,0,0,0,0,0)';
      PINUSE='POWER';
      NO_LOAD_CHECK='Both';
      NO_IO_CHECK='Both';
      NO_ASSERT_CHECK='TRUE';
      NO_DIR_CHECK='TRUE';
      ALLOW_CONNECT='TRUE';
    'NCF_GND3':
      PIN_NUMBER='(0,0,0,0,C2,0,0,0,0,0,0)';
      PINUSE='POWER';
      NO_LOAD_CHECK='Both';
      NO_IO_CHECK='Both';
      NO_ASSERT_CHECK='TRUE';
      NO_DIR_CHECK='TRUE';
      ALLOW_CONNECT='TRUE';
    'NCF_GND4':
      PIN_NUMBER='(0,0,0,0,C34,0,0,0,0,0,0)';
      PINUSE='POWER';
      NO_LOAD_CHECK='Both';
      NO_IO_CHECK='Both';
      NO_ASSERT_CHECK='TRUE';
      NO_DIR_CHECK='TRUE';
      ALLOW_CONNECT='TRUE';
    'NCF_GND5':
      PIN_NUMBER='(0,0,0,0,D1,0,0,0,0,0,0)';
      PINUSE='POWER';
      NO_LOAD_CHECK='Both';
      NO_IO_CHECK='Both';
      NO_ASSERT_CHECK='TRUE';
      NO_DIR_CHECK='TRUE';
      ALLOW_CONNECT='TRUE';
    'NCF_GND6':
      PIN_NUMBER='(0,0,0,0,D35,0,0,0,0,0,0)';
      PINUSE='POWER';
      NO_LOAD_CHECK='Both';
      NO_IO_CHECK='Both';
      NO_ASSERT_CHECK='TRUE';
      NO_DIR_CHECK='TRUE';
      ALLOW_CONNECT='TRUE';
    'NCF_GND7':
      PIN_NUMBER='(0,0,0,0,FE2,0,0,0,0,0,0)';
      PINUSE='POWER';
      NO_LOAD_CHECK='Both';
      NO_IO_CHECK='Both';
      NO_ASSERT_CHECK='TRUE';
      NO_DIR_CHECK='TRUE';
      ALLOW_CONNECT='TRUE';
    'NCF_GND8':
      PIN_NUMBER='(0,0,0,0,FE34,0,0,0,0,0,0)';
      PINUSE='POWER';
      NO_LOAD_CHECK='Both';
      NO_IO_CHECK='Both';
      NO_ASSERT_CHECK='TRUE';
      NO_DIR_CHECK='TRUE';
      ALLOW_CONNECT='TRUE';
    'NCF_GND9':
      PIN_NUMBER='(0,0,0,0,FG1,0,0,0,0,0,0)';
      PINUSE='POWER';
      NO_LOAD_CHECK='Both';
      NO_IO_CHECK='Both';
      NO_ASSERT_CHECK='TRUE';
      NO_DIR_CHECK='TRUE';
      ALLOW_CONNECT='TRUE';
    'NCF_GND10':
      PIN_NUMBER='(0,0,0,0,FG35,0,0,0,0,0,0)';
      PINUSE='POWER';
      NO_LOAD_CHECK='Both';
      NO_IO_CHECK='Both';
      NO_ASSERT_CHECK='TRUE';
      NO_DIR_CHECK='TRUE';
      ALLOW_CONNECT='TRUE';
    'NCF_GND11':
      PIN_NUMBER='(0,0,0,0,FH2,0,0,0,0,0,0)';
      PINUSE='POWER';
      NO_LOAD_CHECK='Both';
      NO_IO_CHECK='Both';
      NO_ASSERT_CHECK='TRUE';
      NO_DIR_CHECK='TRUE';
      ALLOW_CONNECT='TRUE';
    'NCF_GND12':
      PIN_NUMBER='(0,0,0,0,FH34,0,0,0,0,0,0)';
      PINUSE='POWER';
      NO_LOAD_CHECK='Both';
      NO_IO_CHECK='Both';
      NO_ASSERT_CHECK='TRUE';
      NO_DIR_CHECK='TRUE';
      ALLOW_CONNECT='TRUE';
    'GND83':
      PIN_NUMBER='(0,0,0,0,DN22,0,0,0,0,0,0)';
      PINUSE='POWER';
      NO_LOAD_CHECK='Both';
      NO_IO_CHECK='Both';
      NO_ASSERT_CHECK='TRUE';
      NO_DIR_CHECK='TRUE';
      ALLOW_CONNECT='TRUE';
    'GND84':
      PIN_NUMBER='(0,0,0,0,DN32,0,0,0,0,0,0)';
      PINUSE='POWER';
      NO_LOAD_CHECK='Both';
      NO_IO_CHECK='Both';
      NO_ASSERT_CHECK='TRUE';
      NO_DIR_CHECK='TRUE';
      ALLOW_CONNECT='TRUE';
    'GND85':
      PIN_NUMBER='(0,0,0,0,DN4,0,0,0,0,0,0)';
      PINUSE='POWER';
      NO_LOAD_CHECK='Both';
      NO_IO_CHECK='Both';
      NO_ASSERT_CHECK='TRUE';
      NO_DIR_CHECK='TRUE';
      ALLOW_CONNECT='TRUE';
    'GND86':
      PIN_NUMBER='(0,0,0,0,DP2,0,0,0,0,0,0)';
      PINUSE='POWER';
      NO_LOAD_CHECK='Both';
      NO_IO_CHECK='Both';
      NO_ASSERT_CHECK='TRUE';
      NO_DIR_CHECK='TRUE';
      ALLOW_CONNECT='TRUE';
    'GND87':
      PIN_NUMBER='(0,0,0,0,DP34,0,0,0,0,0,0)';
      PINUSE='POWER';
      NO_LOAD_CHECK='Both';
      NO_IO_CHECK='Both';
      NO_ASSERT_CHECK='TRUE';
      NO_DIR_CHECK='TRUE';
      ALLOW_CONNECT='TRUE';
    'GND88':
      PIN_NUMBER='(0,0,0,0,DR1,0,0,0,0,0,0)';
      PINUSE='POWER';
      NO_LOAD_CHECK='Both';
      NO_IO_CHECK='Both';
      NO_ASSERT_CHECK='TRUE';
      NO_DIR_CHECK='TRUE';
      ALLOW_CONNECT='TRUE';
    'GND89':
      PIN_NUMBER='(0,0,0,0,DR35,0,0,0,0,0,0)';
      PINUSE='POWER';
      NO_LOAD_CHECK='Both';
      NO_IO_CHECK='Both';
      NO_ASSERT_CHECK='TRUE';
      NO_DIR_CHECK='TRUE';
      ALLOW_CONNECT='TRUE';
    'GND90':
      PIN_NUMBER='(0,0,0,0,DY13,0,0,0,0,0,0)';
      PINUSE='POWER';
      NO_LOAD_CHECK='Both';
      NO_IO_CHECK='Both';
      NO_ASSERT_CHECK='TRUE';
      NO_DIR_CHECK='TRUE';
      ALLOW_CONNECT='TRUE';
    'GND91':
      PIN_NUMBER='(0,0,0,0,DY22,0,0,0,0,0,0)';
      PINUSE='POWER';
      NO_LOAD_CHECK='Both';
      NO_IO_CHECK='Both';
      NO_ASSERT_CHECK='TRUE';
      NO_DIR_CHECK='TRUE';
      ALLOW_CONNECT='TRUE';
    'GND92':
      PIN_NUMBER='(0,0,0,0,DY32,0,0,0,0,0,0)';
      PINUSE='POWER';
      NO_LOAD_CHECK='Both';
      NO_IO_CHECK='Both';
      NO_ASSERT_CHECK='TRUE';
      NO_DIR_CHECK='TRUE';
      ALLOW_CONNECT='TRUE';
    'GND93':
      PIN_NUMBER='(0,0,0,0,DY4,0,0,0,0,0,0)';
      PINUSE='POWER';
      NO_LOAD_CHECK='Both';
      NO_IO_CHECK='Both';
      NO_ASSERT_CHECK='TRUE';
      NO_DIR_CHECK='TRUE';
      ALLOW_CONNECT='TRUE';
    'GND94':
      PIN_NUMBER='(0,0,0,0,E14,0,0,0,0,0,0)';
      PINUSE='POWER';
      NO_LOAD_CHECK='Both';
      NO_IO_CHECK='Both';
      NO_ASSERT_CHECK='TRUE';
      NO_DIR_CHECK='TRUE';
      ALLOW_CONNECT='TRUE';
    'GND95':
      PIN_NUMBER='(0,0,0,0,E27,0,0,0,0,0,0)';
      PINUSE='POWER';
      NO_LOAD_CHECK='Both';
      NO_IO_CHECK='Both';
      NO_ASSERT_CHECK='TRUE';
      NO_DIR_CHECK='TRUE';
      ALLOW_CONNECT='TRUE';
    'GND96':
      PIN_NUMBER='(0,0,0,0,E33,0,0,0,0,0,0)';
      PINUSE='POWER';
      NO_LOAD_CHECK='Both';
      NO_IO_CHECK='Both';
      NO_ASSERT_CHECK='TRUE';
      NO_DIR_CHECK='TRUE';
      ALLOW_CONNECT='TRUE';
    'GND97':
      PIN_NUMBER='(0,0,0,0,EA2,0,0,0,0,0,0)';
      PINUSE='POWER';
      NO_LOAD_CHECK='Both';
      NO_IO_CHECK='Both';
      NO_ASSERT_CHECK='TRUE';
      NO_DIR_CHECK='TRUE';
      ALLOW_CONNECT='TRUE';
    'GND98':
      PIN_NUMBER='(0,0,0,0,EA34,0,0,0,0,0,0)';
      PINUSE='POWER';
      NO_LOAD_CHECK='Both';
      NO_IO_CHECK='Both';
      NO_ASSERT_CHECK='TRUE';
      NO_DIR_CHECK='TRUE';
      ALLOW_CONNECT='TRUE';
    'GND99':
      PIN_NUMBER='(0,0,0,0,EB1,0,0,0,0,0,0)';
      PINUSE='POWER';
      NO_LOAD_CHECK='Both';
      NO_IO_CHECK='Both';
      NO_ASSERT_CHECK='TRUE';
      NO_DIR_CHECK='TRUE';
      ALLOW_CONNECT='TRUE';
    'GND100':
      PIN_NUMBER='(0,0,0,0,EB35,0,0,0,0,0,0)';
      PINUSE='POWER';
      NO_LOAD_CHECK='Both';
      NO_IO_CHECK='Both';
      NO_ASSERT_CHECK='TRUE';
      NO_DIR_CHECK='TRUE';
      ALLOW_CONNECT='TRUE';
    'GND101':
      PIN_NUMBER='(0,0,0,0,EG13,0,0,0,0,0,0)';
      PINUSE='POWER';
      NO_LOAD_CHECK='Both';
      NO_IO_CHECK='Both';
      NO_ASSERT_CHECK='TRUE';
      NO_DIR_CHECK='TRUE';
      ALLOW_CONNECT='TRUE';
    'GND102':
      PIN_NUMBER='(0,0,0,0,EG22,0,0,0,0,0,0)';
      PINUSE='POWER';
      NO_LOAD_CHECK='Both';
      NO_IO_CHECK='Both';
      NO_ASSERT_CHECK='TRUE';
      NO_DIR_CHECK='TRUE';
      ALLOW_CONNECT='TRUE';
    'GND103':
      PIN_NUMBER='(0,0,0,0,EG32,0,0,0,0,0,0)';
      PINUSE='POWER';
      NO_LOAD_CHECK='Both';
      NO_IO_CHECK='Both';
      NO_ASSERT_CHECK='TRUE';
      NO_DIR_CHECK='TRUE';
      ALLOW_CONNECT='TRUE';
    'GND104':
      PIN_NUMBER='(0,0,0,0,EG4,0,0,0,0,0,0)';
      PINUSE='POWER';
      NO_LOAD_CHECK='Both';
      NO_IO_CHECK='Both';
      NO_ASSERT_CHECK='TRUE';
      NO_DIR_CHECK='TRUE';
      ALLOW_CONNECT='TRUE';
    'GND105':
      PIN_NUMBER='(0,0,0,0,EH2,0,0,0,0,0,0)';
      PINUSE='POWER';
      NO_LOAD_CHECK='Both';
      NO_IO_CHECK='Both';
      NO_ASSERT_CHECK='TRUE';
      NO_DIR_CHECK='TRUE';
      ALLOW_CONNECT='TRUE';
    'GND106':
      PIN_NUMBER='(0,0,0,0,EH34,0,0,0,0,0,0)';
      PINUSE='POWER';
      NO_LOAD_CHECK='Both';
      NO_IO_CHECK='Both';
      NO_ASSERT_CHECK='TRUE';
      NO_DIR_CHECK='TRUE';
      ALLOW_CONNECT='TRUE';
    'GND107':
      PIN_NUMBER='(0,0,0,0,EJ1,0,0,0,0,0,0)';
      PINUSE='POWER';
      NO_LOAD_CHECK='Both';
      NO_IO_CHECK='Both';
      NO_ASSERT_CHECK='TRUE';
      NO_DIR_CHECK='TRUE';
      ALLOW_CONNECT='TRUE';
    'GND108':
      PIN_NUMBER='(0,0,0,0,EJ35,0,0,0,0,0,0)';
      PINUSE='POWER';
      NO_LOAD_CHECK='Both';
      NO_IO_CHECK='Both';
      NO_ASSERT_CHECK='TRUE';
      NO_DIR_CHECK='TRUE';
      ALLOW_CONNECT='TRUE';
    'GND109':
      PIN_NUMBER='(0,0,0,0,EP13,0,0,0,0,0,0)';
      PINUSE='POWER';
      NO_LOAD_CHECK='Both';
      NO_IO_CHECK='Both';
      NO_ASSERT_CHECK='TRUE';
      NO_DIR_CHECK='TRUE';
      ALLOW_CONNECT='TRUE';
    'GND110':
      PIN_NUMBER='(0,0,0,0,EP22,0,0,0,0,0,0)';
      PINUSE='POWER';
      NO_LOAD_CHECK='Both';
      NO_IO_CHECK='Both';
      NO_ASSERT_CHECK='TRUE';
      NO_DIR_CHECK='TRUE';
      ALLOW_CONNECT='TRUE';
    'GND111':
      PIN_NUMBER='(0,0,0,0,EP32,0,0,0,0,0,0)';
      PINUSE='POWER';
      NO_LOAD_CHECK='Both';
      NO_IO_CHECK='Both';
      NO_ASSERT_CHECK='TRUE';
      NO_DIR_CHECK='TRUE';
      ALLOW_CONNECT='TRUE';
    'GND112':
      PIN_NUMBER='(0,0,0,0,EP4,0,0,0,0,0,0)';
      PINUSE='POWER';
      NO_LOAD_CHECK='Both';
      NO_IO_CHECK='Both';
      NO_ASSERT_CHECK='TRUE';
      NO_DIR_CHECK='TRUE';
      ALLOW_CONNECT='TRUE';
    'GND113':
      PIN_NUMBER='(0,0,0,0,ER2,0,0,0,0,0,0)';
      PINUSE='POWER';
      NO_LOAD_CHECK='Both';
      NO_IO_CHECK='Both';
      NO_ASSERT_CHECK='TRUE';
      NO_DIR_CHECK='TRUE';
      ALLOW_CONNECT='TRUE';
    'GND114':
      PIN_NUMBER='(0,0,0,0,ER34,0,0,0,0,0,0)';
      PINUSE='POWER';
      NO_LOAD_CHECK='Both';
      NO_IO_CHECK='Both';
      NO_ASSERT_CHECK='TRUE';
      NO_DIR_CHECK='TRUE';
      ALLOW_CONNECT='TRUE';
    'GND115':
      PIN_NUMBER='(0,0,0,0,ET1,0,0,0,0,0,0)';
      PINUSE='POWER';
      NO_LOAD_CHECK='Both';
      NO_IO_CHECK='Both';
      NO_ASSERT_CHECK='TRUE';
      NO_DIR_CHECK='TRUE';
      ALLOW_CONNECT='TRUE';
    'GND116':
      PIN_NUMBER='(0,0,0,0,ET35,0,0,0,0,0,0)';
      PINUSE='POWER';
      NO_LOAD_CHECK='Both';
      NO_IO_CHECK='Both';
      NO_ASSERT_CHECK='TRUE';
      NO_DIR_CHECK='TRUE';
      ALLOW_CONNECT='TRUE';
    'GND117':
      PIN_NUMBER='(0,0,0,0,FA15,0,0,0,0,0,0)';
      PINUSE='POWER';
      NO_LOAD_CHECK='Both';
      NO_IO_CHECK='Both';
      NO_ASSERT_CHECK='TRUE';
      NO_DIR_CHECK='TRUE';
      ALLOW_CONNECT='TRUE';
    'GND118':
      PIN_NUMBER='(0,0,0,0,FA32,0,0,0,0,0,0)';
      PINUSE='POWER';
      NO_LOAD_CHECK='Both';
      NO_IO_CHECK='Both';
      NO_ASSERT_CHECK='TRUE';
      NO_DIR_CHECK='TRUE';
      ALLOW_CONNECT='TRUE';
    'GND119':
      PIN_NUMBER='(0,0,0,0,FB2,0,0,0,0,0,0)';
      PINUSE='POWER';
      NO_LOAD_CHECK='Both';
      NO_IO_CHECK='Both';
      NO_ASSERT_CHECK='TRUE';
      NO_DIR_CHECK='TRUE';
      ALLOW_CONNECT='TRUE';
    'GND120':
      PIN_NUMBER='(0,0,0,0,FB34,0,0,0,0,0,0)';
      PINUSE='POWER';
      NO_LOAD_CHECK='Both';
      NO_IO_CHECK='Both';
      NO_ASSERT_CHECK='TRUE';
      NO_DIR_CHECK='TRUE';
      ALLOW_CONNECT='TRUE';
    'GND121':
      PIN_NUMBER='(0,0,0,0,FC19,0,0,0,0,0,0)';
      PINUSE='POWER';
      NO_LOAD_CHECK='Both';
      NO_IO_CHECK='Both';
      NO_ASSERT_CHECK='TRUE';
      NO_DIR_CHECK='TRUE';
      ALLOW_CONNECT='TRUE';
    'GND122':
      PIN_NUMBER='(0,0,0,0,FC23,0,0,0,0,0,0)';
      PINUSE='POWER';
      NO_LOAD_CHECK='Both';
      NO_IO_CHECK='Both';
      NO_ASSERT_CHECK='TRUE';
      NO_DIR_CHECK='TRUE';
      ALLOW_CONNECT='TRUE';
    'GND123':
      PIN_NUMBER='(0,0,0,0,FC25,0,0,0,0,0,0)';
      PINUSE='POWER';
      NO_LOAD_CHECK='Both';
      NO_IO_CHECK='Both';
      NO_ASSERT_CHECK='TRUE';
      NO_DIR_CHECK='TRUE';
      ALLOW_CONNECT='TRUE';
    'GND124':
      PIN_NUMBER='(0,0,0,0,FC28,0,0,0,0,0,0)';
      PINUSE='POWER';
      NO_LOAD_CHECK='Both';
      NO_IO_CHECK='Both';
      NO_ASSERT_CHECK='TRUE';
      NO_DIR_CHECK='TRUE';
      ALLOW_CONNECT='TRUE';
    'GND125':
      PIN_NUMBER='(0,0,0,0,FC3,0,0,0,0,0,0)';
      PINUSE='POWER';
      NO_LOAD_CHECK='Both';
      NO_IO_CHECK='Both';
      NO_ASSERT_CHECK='TRUE';
      NO_DIR_CHECK='TRUE';
      ALLOW_CONNECT='TRUE';
    'GND126':
      PIN_NUMBER='(0,0,0,0,FC6,0,0,0,0,0,0)';
      PINUSE='POWER';
      NO_LOAD_CHECK='Both';
      NO_IO_CHECK='Both';
      NO_ASSERT_CHECK='TRUE';
      NO_DIR_CHECK='TRUE';
      ALLOW_CONNECT='TRUE';
    'GND127':
      PIN_NUMBER='(0,0,0,0,FC9,0,0,0,0,0,0)';
      PINUSE='POWER';
      NO_LOAD_CHECK='Both';
      NO_IO_CHECK='Both';
      NO_ASSERT_CHECK='TRUE';
      NO_DIR_CHECK='TRUE';
      ALLOW_CONNECT='TRUE';
    'GND128':
      PIN_NUMBER='(0,0,0,0,FD1,0,0,0,0,0,0)';
      PINUSE='POWER';
      NO_LOAD_CHECK='Both';
      NO_IO_CHECK='Both';
      NO_ASSERT_CHECK='TRUE';
      NO_DIR_CHECK='TRUE';
      ALLOW_CONNECT='TRUE';
    'GND129':
      PIN_NUMBER='(0,0,0,0,FD35,0,0,0,0,0,0)';
      PINUSE='POWER';
      NO_LOAD_CHECK='Both';
      NO_IO_CHECK='Both';
      NO_ASSERT_CHECK='TRUE';
      NO_DIR_CHECK='TRUE';
      ALLOW_CONNECT='TRUE';
    'GND130':
      PIN_NUMBER='(0,0,0,0,FF14,0,0,0,0,0,0)';
      PINUSE='POWER';
      NO_LOAD_CHECK='Both';
      NO_IO_CHECK='Both';
      NO_ASSERT_CHECK='TRUE';
      NO_DIR_CHECK='TRUE';
      ALLOW_CONNECT='TRUE';
    'GND131':
      PIN_NUMBER='(0,0,0,0,FF21,0,0,0,0,0,0)';
      PINUSE='POWER';
      NO_LOAD_CHECK='Both';
      NO_IO_CHECK='Both';
      NO_ASSERT_CHECK='TRUE';
      NO_DIR_CHECK='TRUE';
      ALLOW_CONNECT='TRUE';
    'GND132':
      PIN_NUMBER='(0,0,0,0,FJ12,0,0,0,0,0,0)';
      PINUSE='POWER';
      NO_LOAD_CHECK='Both';
      NO_IO_CHECK='Both';
      NO_ASSERT_CHECK='TRUE';
      NO_DIR_CHECK='TRUE';
      ALLOW_CONNECT='TRUE';
    'GND133':
      PIN_NUMBER='(0,0,0,0,FJ19,0,0,0,0,0,0)';
      PINUSE='POWER';
      NO_LOAD_CHECK='Both';
      NO_IO_CHECK='Both';
      NO_ASSERT_CHECK='TRUE';
      NO_DIR_CHECK='TRUE';
      ALLOW_CONNECT='TRUE';
    'GND134':
      PIN_NUMBER='(0,0,0,0,H12,0,0,0,0,0,0)';
      PINUSE='POWER';
      NO_LOAD_CHECK='Both';
      NO_IO_CHECK='Both';
      NO_ASSERT_CHECK='TRUE';
      NO_DIR_CHECK='TRUE';
      ALLOW_CONNECT='TRUE';
    'GND135':
      PIN_NUMBER='(0,0,0,0,H16,0,0,0,0,0,0)';
      PINUSE='POWER';
      NO_LOAD_CHECK='Both';
      NO_IO_CHECK='Both';
      NO_ASSERT_CHECK='TRUE';
      NO_DIR_CHECK='TRUE';
      ALLOW_CONNECT='TRUE';
    'GND136':
      PIN_NUMBER='(0,0,0,0,H19,0,0,0,0,0,0)';
      PINUSE='POWER';
      NO_LOAD_CHECK='Both';
      NO_IO_CHECK='Both';
      NO_ASSERT_CHECK='TRUE';
      NO_DIR_CHECK='TRUE';
      ALLOW_CONNECT='TRUE';
    'GND137':
      PIN_NUMBER='(0,0,0,0,H31,0,0,0,0,0,0)';
      PINUSE='POWER';
      NO_LOAD_CHECK='Both';
      NO_IO_CHECK='Both';
      NO_ASSERT_CHECK='TRUE';
      NO_DIR_CHECK='TRUE';
      ALLOW_CONNECT='TRUE';
    'GND138':
      PIN_NUMBER='(0,0,0,0,J22,0,0,0,0,0,0)';
      PINUSE='POWER';
      NO_LOAD_CHECK='Both';
      NO_IO_CHECK='Both';
      NO_ASSERT_CHECK='TRUE';
      NO_DIR_CHECK='TRUE';
      ALLOW_CONNECT='TRUE';
    'GND139':
      PIN_NUMBER='(0,0,0,0,J4,0,0,0,0,0,0)';
      PINUSE='POWER';
      NO_LOAD_CHECK='Both';
      NO_IO_CHECK='Both';
      NO_ASSERT_CHECK='TRUE';
      NO_DIR_CHECK='TRUE';
      ALLOW_CONNECT='TRUE';
    'GND140':
      PIN_NUMBER='(0,0,0,0,K2,0,0,0,0,0,0)';
      PINUSE='POWER';
      NO_LOAD_CHECK='Both';
      NO_IO_CHECK='Both';
      NO_ASSERT_CHECK='TRUE';
      NO_DIR_CHECK='TRUE';
      ALLOW_CONNECT='TRUE';
    'GND141':
      PIN_NUMBER='(0,0,0,0,K34,0,0,0,0,0,0)';
      PINUSE='POWER';
      NO_LOAD_CHECK='Both';
      NO_IO_CHECK='Both';
      NO_ASSERT_CHECK='TRUE';
      NO_DIR_CHECK='TRUE';
      ALLOW_CONNECT='TRUE';
    'GND142':
      PIN_NUMBER='(0,0,0,0,L1,0,0,0,0,0,0)';
      PINUSE='POWER';
      NO_LOAD_CHECK='Both';
      NO_IO_CHECK='Both';
      NO_ASSERT_CHECK='TRUE';
      NO_DIR_CHECK='TRUE';
      ALLOW_CONNECT='TRUE';
    'GND143':
      PIN_NUMBER='(0,0,0,0,L35,0,0,0,0,0,0)';
      PINUSE='POWER';
      NO_LOAD_CHECK='Both';
      NO_IO_CHECK='Both';
      NO_ASSERT_CHECK='TRUE';
      NO_DIR_CHECK='TRUE';
      ALLOW_CONNECT='TRUE';
    'GND144':
      PIN_NUMBER='(0,0,0,0,T13,0,0,0,0,0,0)';
      PINUSE='POWER';
      NO_LOAD_CHECK='Both';
      NO_IO_CHECK='Both';
      NO_ASSERT_CHECK='TRUE';
      NO_DIR_CHECK='TRUE';
      ALLOW_CONNECT='TRUE';
    'GND145':
      PIN_NUMBER='(0,0,0,0,T22,0,0,0,0,0,0)';
      PINUSE='POWER';
      NO_LOAD_CHECK='Both';
      NO_IO_CHECK='Both';
      NO_ASSERT_CHECK='TRUE';
      NO_DIR_CHECK='TRUE';
      ALLOW_CONNECT='TRUE';
    'GND146':
      PIN_NUMBER='(0,0,0,0,T32,0,0,0,0,0,0)';
      PINUSE='POWER';
      NO_LOAD_CHECK='Both';
      NO_IO_CHECK='Both';
      NO_ASSERT_CHECK='TRUE';
      NO_DIR_CHECK='TRUE';
      ALLOW_CONNECT='TRUE';
    'GND147':
      PIN_NUMBER='(0,0,0,0,T4,0,0,0,0,0,0)';
      PINUSE='POWER';
      NO_LOAD_CHECK='Both';
      NO_IO_CHECK='Both';
      NO_ASSERT_CHECK='TRUE';
      NO_DIR_CHECK='TRUE';
      ALLOW_CONNECT='TRUE';
    'GND148':
      PIN_NUMBER='(0,0,0,0,U2,0,0,0,0,0,0)';
      PINUSE='POWER';
      NO_LOAD_CHECK='Both';
      NO_IO_CHECK='Both';
      NO_ASSERT_CHECK='TRUE';
      NO_DIR_CHECK='TRUE';
      ALLOW_CONNECT='TRUE';
    'GND149':
      PIN_NUMBER='(0,0,0,0,U34,0,0,0,0,0,0)';
      PINUSE='POWER';
      NO_LOAD_CHECK='Both';
      NO_IO_CHECK='Both';
      NO_ASSERT_CHECK='TRUE';
      NO_DIR_CHECK='TRUE';
      ALLOW_CONNECT='TRUE';
    'GND150':
      PIN_NUMBER='(0,0,0,0,V1,0,0,0,0,0,0)';
      PINUSE='POWER';
      NO_LOAD_CHECK='Both';
      NO_IO_CHECK='Both';
      NO_ASSERT_CHECK='TRUE';
      NO_DIR_CHECK='TRUE';
      ALLOW_CONNECT='TRUE';
    'GND151':
      PIN_NUMBER='(0,0,0,0,V35,0,0,0,0,0,0)';
      PINUSE='POWER';
      NO_LOAD_CHECK='Both';
      NO_IO_CHECK='Both';
      NO_ASSERT_CHECK='TRUE';
      NO_DIR_CHECK='TRUE';
      ALLOW_CONNECT='TRUE';
    'A_PETP0':
      PIN_NUMBER='(0,0,0,0,0,M26,0,0,0,0,0)';
      OUTPUT_LOAD='(1.0,-1.0)';
    'A_PETN0':
      PIN_NUMBER='(0,0,0,0,0,P29,0,0,0,0,0)';
      OUTPUT_LOAD='(1.0,-1.0)';
    'A_PETP1':
      PIN_NUMBER='(0,0,0,0,0,W26,0,0,0,0,0)';
      OUTPUT_LOAD='(1.0,-1.0)';
    'A_PETN1':
      PIN_NUMBER='(0,0,0,0,0,AA29,0,0,0,0,0)';
      OUTPUT_LOAD='(1.0,-1.0)';
    'A_PETP2':
      PIN_NUMBER='(0,0,0,0,0,AF26,0,0,0,0,0)';
      OUTPUT_LOAD='(1.0,-1.0)';
    'A_PETN2':
      PIN_NUMBER='(0,0,0,0,0,AH29,0,0,0,0,0)';
      OUTPUT_LOAD='(1.0,-1.0)';
    'A_PETP3':
      PIN_NUMBER='(0,0,0,0,0,AN26,0,0,0,0,0)';
      OUTPUT_LOAD='(1.0,-1.0)';
    'A_PETN3':
      PIN_NUMBER='(0,0,0,0,0,AR29,0,0,0,0,0)';
      OUTPUT_LOAD='(1.0,-1.0)';
    'A_PETP4':
      PIN_NUMBER='(0,0,0,0,0,AY26,0,0,0,0,0)';
      OUTPUT_LOAD='(1.0,-1.0)';
    'A_PETN4':
      PIN_NUMBER='(0,0,0,0,0,BB29,0,0,0,0,0)';
      OUTPUT_LOAD='(1.0,-1.0)';
    'A_PETP5':
      PIN_NUMBER='(0,0,0,0,0,BG26,0,0,0,0,0)';
      OUTPUT_LOAD='(1.0,-1.0)';
    'A_PETN5':
      PIN_NUMBER='(0,0,0,0,0,BJ29,0,0,0,0,0)';
      OUTPUT_LOAD='(1.0,-1.0)';
    'A_PETP6':
      PIN_NUMBER='(0,0,0,0,0,BP26,0,0,0,0,0)';
      OUTPUT_LOAD='(1.0,-1.0)';
    'A_PETN6':
      PIN_NUMBER='(0,0,0,0,0,BT29,0,0,0,0,0)';
      OUTPUT_LOAD='(1.0,-1.0)';
    'A_PETP7':
      PIN_NUMBER='(0,0,0,0,0,CA26,0,0,0,0,0)';
      OUTPUT_LOAD='(1.0,-1.0)';
    'A_PETN7':
      PIN_NUMBER='(0,0,0,0,0,CC29,0,0,0,0,0)';
      OUTPUT_LOAD='(1.0,-1.0)';
    'A_PETP8':
      PIN_NUMBER='(0,0,0,0,0,0,CH26,0,0,0,0)';
      OUTPUT_LOAD='(1.0,-1.0)';
    'A_PETN8':
      PIN_NUMBER='(0,0,0,0,0,0,CK29,0,0,0,0)';
      OUTPUT_LOAD='(1.0,-1.0)';
    'A_PETP9':
      PIN_NUMBER='(0,0,0,0,0,0,CR26,0,0,0,0)';
      OUTPUT_LOAD='(1.0,-1.0)';
    'A_PETN9':
      PIN_NUMBER='(0,0,0,0,0,0,CU29,0,0,0,0)';
      OUTPUT_LOAD='(1.0,-1.0)';
    'A_PETP10':
      PIN_NUMBER='(0,0,0,0,0,0,DB26,0,0,0,0)';
      OUTPUT_LOAD='(1.0,-1.0)';
    'A_PETN10':
      PIN_NUMBER='(0,0,0,0,0,0,DD29,0,0,0,0)';
      OUTPUT_LOAD='(1.0,-1.0)';
    'A_PETP11':
      PIN_NUMBER='(0,0,0,0,0,0,DJ26,0,0,0,0)';
      OUTPUT_LOAD='(1.0,-1.0)';
    'A_PETN11':
      PIN_NUMBER='(0,0,0,0,0,0,DL29,0,0,0,0)';
      OUTPUT_LOAD='(1.0,-1.0)';
    'A_PETP12':
      PIN_NUMBER='(0,0,0,0,0,0,DT26,0,0,0,0)';
      OUTPUT_LOAD='(1.0,-1.0)';
    'A_PETN12':
      PIN_NUMBER='(0,0,0,0,0,0,DV29,0,0,0,0)';
      OUTPUT_LOAD='(1.0,-1.0)';
    'A_PETP13':
      PIN_NUMBER='(0,0,0,0,0,0,EC26,0,0,0,0)';
      OUTPUT_LOAD='(1.0,-1.0)';
    'A_PETN13':
      PIN_NUMBER='(0,0,0,0,0,0,EE29,0,0,0,0)';
      OUTPUT_LOAD='(1.0,-1.0)';
    'A_PETP14':
      PIN_NUMBER='(0,0,0,0,0,0,EK26,0,0,0,0)';
      OUTPUT_LOAD='(1.0,-1.0)';
    'A_PETN14':
      PIN_NUMBER='(0,0,0,0,0,0,EM29,0,0,0,0)';
      OUTPUT_LOAD='(1.0,-1.0)';
    'A_PETP15':
      PIN_NUMBER='(0,0,0,0,0,0,EU26,0,0,0,0)';
      OUTPUT_LOAD='(1.0,-1.0)';
    'A_PETN15':
      PIN_NUMBER='(0,0,0,0,0,0,EW29,0,0,0,0)';
      OUTPUT_LOAD='(1.0,-1.0)';
    'B_PERP0':
      PIN_NUMBER='(0,0,0,0,0,0,0,N34,0,0,0)';
      INPUT_LOAD='(-0.01,0.01)';
    'B_PERN0':
      PIN_NUMBER='(0,0,0,0,0,0,0,R35,0,0,0)';
      INPUT_LOAD='(-0.01,0.01)';
    'B_PERP1':
      PIN_NUMBER='(0,0,0,0,0,0,0,Y34,0,0,0)';
      INPUT_LOAD='(-0.01,0.01)';
    'B_PERN1':
      PIN_NUMBER='(0,0,0,0,0,0,0,AB35,0,0,0)';
      INPUT_LOAD='(-0.01,0.01)';
    'B_PERP2':
      PIN_NUMBER='(0,0,0,0,0,0,0,AG34,0,0,0)';
      INPUT_LOAD='(-0.01,0.01)';
    'B_PERN2':
      PIN_NUMBER='(0,0,0,0,0,0,0,AJ35,0,0,0)';
      INPUT_LOAD='(-0.01,0.01)';
    'B_PERP3':
      PIN_NUMBER='(0,0,0,0,0,0,0,AP34,0,0,0)';
      INPUT_LOAD='(-0.01,0.01)';
    'B_PERN3':
      PIN_NUMBER='(0,0,0,0,0,0,0,AT35,0,0,0)';
      INPUT_LOAD='(-0.01,0.01)';
    'B_PERP4':
      PIN_NUMBER='(0,0,0,0,0,0,0,BA34,0,0,0)';
      INPUT_LOAD='(-0.01,0.01)';
    'B_PERN4':
      PIN_NUMBER='(0,0,0,0,0,0,0,BC35,0,0,0)';
      INPUT_LOAD='(-0.01,0.01)';
    'B_PERP5':
      PIN_NUMBER='(0,0,0,0,0,0,0,BH34,0,0,0)';
      INPUT_LOAD='(-0.01,0.01)';
    'B_PERN5':
      PIN_NUMBER='(0,0,0,0,0,0,0,BK35,0,0,0)';
      INPUT_LOAD='(-0.01,0.01)';
    'B_PERP6':
      PIN_NUMBER='(0,0,0,0,0,0,0,BR34,0,0,0)';
      INPUT_LOAD='(-0.01,0.01)';
    'B_PERN6':
      PIN_NUMBER='(0,0,0,0,0,0,0,BU35,0,0,0)';
      INPUT_LOAD='(-0.01,0.01)';
    'B_PERP7':
      PIN_NUMBER='(0,0,0,0,0,0,0,CB34,0,0,0)';
      INPUT_LOAD='(-0.01,0.01)';
    'B_PERN7':
      PIN_NUMBER='(0,0,0,0,0,0,0,CD35,0,0,0)';
      INPUT_LOAD='(-0.01,0.01)';
    'B_PERP8':
      PIN_NUMBER='(0,0,0,0,0,0,0,0,CJ34,0,0)';
      INPUT_LOAD='(-0.01,0.01)';
    'B_PERN8':
      PIN_NUMBER='(0,0,0,0,0,0,0,0,CL35,0,0)';
      INPUT_LOAD='(-0.01,0.01)';
    'B_PERP9':
      PIN_NUMBER='(0,0,0,0,0,0,0,0,CT34,0,0)';
      INPUT_LOAD='(-0.01,0.01)';
    'B_PERN9':
      PIN_NUMBER='(0,0,0,0,0,0,0,0,CV35,0,0)';
      INPUT_LOAD='(-0.01,0.01)';
    'B_PERP10':
      PIN_NUMBER='(0,0,0,0,0,0,0,0,DC34,0,0)';
      INPUT_LOAD='(-0.01,0.01)';
    'B_PERN10':
      PIN_NUMBER='(0,0,0,0,0,0,0,0,DE35,0,0)';
      INPUT_LOAD='(-0.01,0.01)';
    'B_PERP11':
      PIN_NUMBER='(0,0,0,0,0,0,0,0,DK34,0,0)';
      INPUT_LOAD='(-0.01,0.01)';
    'B_PERN11':
      PIN_NUMBER='(0,0,0,0,0,0,0,0,DM35,0,0)';
      INPUT_LOAD='(-0.01,0.01)';
    'B_PERP12':
      PIN_NUMBER='(0,0,0,0,0,0,0,0,DU34,0,0)';
      INPUT_LOAD='(-0.01,0.01)';
    'B_PERN12':
      PIN_NUMBER='(0,0,0,0,0,0,0,0,DW35,0,0)';
      INPUT_LOAD='(-0.01,0.01)';
    'B_PERP13':
      PIN_NUMBER='(0,0,0,0,0,0,0,0,ED34,0,0)';
      INPUT_LOAD='(-0.01,0.01)';
    'B_PERN13':
      PIN_NUMBER='(0,0,0,0,0,0,0,0,EF35,0,0)';
      INPUT_LOAD='(-0.01,0.01)';
    'B_PERP14':
      PIN_NUMBER='(0,0,0,0,0,0,0,0,EL34,0,0)';
      INPUT_LOAD='(-0.01,0.01)';
    'B_PERN14':
      PIN_NUMBER='(0,0,0,0,0,0,0,0,EN35,0,0)';
      INPUT_LOAD='(-0.01,0.01)';
    'B_PERP15':
      PIN_NUMBER='(0,0,0,0,0,0,0,0,EV34,0,0)';
      INPUT_LOAD='(-0.01,0.01)';
    'B_PERN15':
      PIN_NUMBER='(0,0,0,0,0,0,0,0,EY35,0,0)';
      INPUT_LOAD='(-0.01,0.01)';
    'B_PETP0':
      PIN_NUMBER='(0,0,0,0,0,0,0,0,0,M7,0)';
      OUTPUT_LOAD='(1.0,-1.0)';
    'B_PETN0':
      PIN_NUMBER='(0,0,0,0,0,0,0,0,0,P10,0)';
      OUTPUT_LOAD='(1.0,-1.0)';
    'B_PETP1':
      PIN_NUMBER='(0,0,0,0,0,0,0,0,0,W7,0)';
      OUTPUT_LOAD='(1.0,-1.0)';
    'B_PETN1':
      PIN_NUMBER='(0,0,0,0,0,0,0,0,0,AA10,0)';
      OUTPUT_LOAD='(1.0,-1.0)';
    'B_PETP2':
      PIN_NUMBER='(0,0,0,0,0,0,0,0,0,AF7,0)';
      OUTPUT_LOAD='(1.0,-1.0)';
    'B_PETN2':
      PIN_NUMBER='(0,0,0,0,0,0,0,0,0,AH10,0)';
      OUTPUT_LOAD='(1.0,-1.0)';
    'B_PETP3':
      PIN_NUMBER='(0,0,0,0,0,0,0,0,0,AN7,0)';
      OUTPUT_LOAD='(1.0,-1.0)';
    'B_PETN3':
      PIN_NUMBER='(0,0,0,0,0,0,0,0,0,AR10,0)';
      OUTPUT_LOAD='(1.0,-1.0)';
    'B_PETP4':
      PIN_NUMBER='(0,0,0,0,0,0,0,0,0,AY7,0)';
      OUTPUT_LOAD='(1.0,-1.0)';
    'B_PETN4':
      PIN_NUMBER='(0,0,0,0,0,0,0,0,0,BB10,0)';
      OUTPUT_LOAD='(1.0,-1.0)';
    'B_PETP5':
      PIN_NUMBER='(0,0,0,0,0,0,0,0,0,BG7,0)';
      OUTPUT_LOAD='(1.0,-1.0)';
    'B_PETN5':
      PIN_NUMBER='(0,0,0,0,0,0,0,0,0,BJ10,0)';
      OUTPUT_LOAD='(1.0,-1.0)';
    'B_PETP6':
      PIN_NUMBER='(0,0,0,0,0,0,0,0,0,BP7,0)';
      OUTPUT_LOAD='(1.0,-1.0)';
    'B_PETN6':
      PIN_NUMBER='(0,0,0,0,0,0,0,0,0,BT10,0)';
      OUTPUT_LOAD='(1.0,-1.0)';
    'B_PETP7':
      PIN_NUMBER='(0,0,0,0,0,0,0,0,0,CA7,0)';
      OUTPUT_LOAD='(1.0,-1.0)';
    'B_PETN7':
      PIN_NUMBER='(0,0,0,0,0,0,0,0,0,CC10,0)';
      OUTPUT_LOAD='(1.0,-1.0)';
    'B_PETP8':
      PIN_NUMBER='(0,0,0,0,0,0,0,0,0,0,CH7)';
      OUTPUT_LOAD='(1.0,-1.0)';
    'B_PETN8':
      PIN_NUMBER='(0,0,0,0,0,0,0,0,0,0,CK10)';
      OUTPUT_LOAD='(1.0,-1.0)';
    'B_PETP9':
      PIN_NUMBER='(0,0,0,0,0,0,0,0,0,0,CR7)';
      OUTPUT_LOAD='(1.0,-1.0)';
    'B_PETN9':
      PIN_NUMBER='(0,0,0,0,0,0,0,0,0,0,CU10)';
      OUTPUT_LOAD='(1.0,-1.0)';
    'B_PETP10':
      PIN_NUMBER='(0,0,0,0,0,0,0,0,0,0,DB7)';
      OUTPUT_LOAD='(1.0,-1.0)';
    'B_PETN10':
      PIN_NUMBER='(0,0,0,0,0,0,0,0,0,0,DD10)';
      OUTPUT_LOAD='(1.0,-1.0)';
    'B_PETP11':
      PIN_NUMBER='(0,0,0,0,0,0,0,0,0,0,DJ7)';
      OUTPUT_LOAD='(1.0,-1.0)';
    'B_PETN11':
      PIN_NUMBER='(0,0,0,0,0,0,0,0,0,0,DL10)';
      OUTPUT_LOAD='(1.0,-1.0)';
    'B_PETP12':
      PIN_NUMBER='(0,0,0,0,0,0,0,0,0,0,DT7)';
      OUTPUT_LOAD='(1.0,-1.0)';
    'B_PETN12':
      PIN_NUMBER='(0,0,0,0,0,0,0,0,0,0,DV10)';
      OUTPUT_LOAD='(1.0,-1.0)';
    'B_PETP13':
      PIN_NUMBER='(0,0,0,0,0,0,0,0,0,0,EC7)';
      OUTPUT_LOAD='(1.0,-1.0)';
    'B_PETN13':
      PIN_NUMBER='(0,0,0,0,0,0,0,0,0,0,EE10)';
      OUTPUT_LOAD='(1.0,-1.0)';
    'B_PETP14':
      PIN_NUMBER='(0,0,0,0,0,0,0,0,0,0,EK7)';
      OUTPUT_LOAD='(1.0,-1.0)';
    'B_PETN14':
      PIN_NUMBER='(0,0,0,0,0,0,0,0,0,0,EM10)';
      OUTPUT_LOAD='(1.0,-1.0)';
    'B_PETP15':
      PIN_NUMBER='(0,0,0,0,0,0,0,0,0,0,EU7)';
      OUTPUT_LOAD='(1.0,-1.0)';
    'B_PETN15':
      PIN_NUMBER='(0,0,0,0,0,0,0,0,0,0,EW10)';
      OUTPUT_LOAD='(1.0,-1.0)';
  end_pin;
  body
    PART_NAME='PT5161LRS';
    BODY_NAME='PT5161LRS';
    PHYS_DES_PREFIX='U';
    CLASS='IC';
  end_body;
end_primitive;

END.
